(kicad_pcb
	(version 20260206)
	(generator "pcbnew")
	(generator_version "10.0")
	(general
		(thickness 1.6)
		(legacy_teardrops no)
	)
	(paper "A4")
	(title_block
		(title "03242023_DA0F0TMBIJ0_F0T_Motherboard_J_brd_V01_OCP.brd")
		(comment 1 "Grand Teton / footprints 384-388 of 6105")
	)
	(layers
		(0 "F.Cu" signal "TOP")
		(4 "In1.Cu" signal "GND")
		(6 "In2.Cu" signal "IN1")
		(8 "In3.Cu" signal "GND1")
		(10 "In4.Cu" signal "IN2")
		(12 "In5.Cu" signal "GND2")
		(14 "In6.Cu" signal "IN3")
		(16 "In7.Cu" signal "GND3")
		(18 "In8.Cu" signal "VCC")
		(20 "In9.Cu" signal "VCC1")
		(22 "In10.Cu" signal "GND4")
		(24 "In11.Cu" signal "IN4")
		(26 "In12.Cu" signal "GND5")
		(28 "In13.Cu" signal "IN5")
		(30 "In14.Cu" signal "GND6")
		(32 "In15.Cu" signal "IN6")
		(34 "In16.Cu" signal "GND7")
		(2 "B.Cu" signal "BOTTOM")
		(9 "F.Adhes" user "F.Adhesive")
		(11 "B.Adhes" user "B.Adhesive")
		(13 "F.Paste" user "Package Geometry/Pastemask Top")
		(15 "B.Paste" user "Package Geometry/Pastemask Bottom")
		(5 "F.SilkS" user "Ref Des/Silkscreen Top")
		(7 "B.SilkS" user "Ref Des/Silkscreen Bottom")
		(1 "F.Mask" user "Board Geometry/Soldermask Top")
		(3 "B.Mask" user "Board Geometry/Soldermask Bottom")
		(17 "Dwgs.User" user "User.Drawings")
		(19 "Cmts.User" user "User.Comments")
		(21 "Eco1.User" user "User.Eco1")
		(23 "Eco2.User" user "User.Eco2")
		(25 "Edge.Cuts" user "Board Geometry/Outline")
		(27 "Margin" user)
		(31 "F.CrtYd" user "Package Geometry/Place Bound Top")
		(29 "B.CrtYd" user "Package Geometry/Place Bound Bottom")
		(35 "F.Fab" user "Ref Des/Assembly Top")
		(33 "B.Fab" user "Ref Des/Assembly Bottom")
	)
	(footprint ""
		(layer "F.Cu")
		(at 377.579636 -337.126326)
		(property "Reference" "PU9_P0_5"
			(at -3.567176 -7.230872 0)
			(unlocked yes)
			(layer "F.SilkS")
			(effects
				(font
					(size 0.7874 0.5842)
					(thickness 0.1524)
				)
				(justify left)
			)
		)
		(property "Value" ""
			(at 0 0 0)
			(layer "F.Fab")
			(effects
				(font
					(size 1.27 1.27)
				)
			)
		)
		(duplicate_pad_numbers_are_jumpers no)
		(fp_line
			(start -2.500122 -2.999994)
			(end -2.24409 -2.999994)
			(stroke
				(width 0.1524)
				(type default)
			)
			(layer "F.SilkS")
		)
		(fp_line
			(start -2.500122 -2.529078)
			(end -2.500122 -2.999994)
			(stroke
				(width 0.1524)
				(type default)
			)
			(layer "F.SilkS")
		)
		(fp_line
			(start -2.500122 0.6604)
			(end -2.500122 0.229108)
			(stroke
				(width 0.1524)
				(type default)
			)
			(layer "F.SilkS")
		)
		(fp_line
			(start -2.500122 2.999994)
			(end -2.500122 2.339594)
			(stroke
				(width 0.1524)
				(type default)
			)
			(layer "F.SilkS")
		)
		(fp_line
			(start -2.2987 2.999994)
			(end -2.500122 2.999994)
			(stroke
				(width 0.1524)
				(type default)
			)
			(layer "F.SilkS")
		)
		(fp_line
			(start 2.31394 -2.999994)
			(end 2.500122 -2.999994)
			(stroke
				(width 0.1524)
				(type default)
			)
			(layer "F.SilkS")
		)
		(fp_line
			(start 2.500122 -2.999994)
			(end 2.500122 -2.44348)
			(stroke
				(width 0.1524)
				(type default)
			)
			(layer "F.SilkS")
		)
		(fp_line
			(start 2.500122 2.339594)
			(end 2.500122 2.999994)
			(stroke
				(width 0.1524)
				(type default)
			)
			(layer "F.SilkS")
		)
		(fp_line
			(start 2.500122 2.999994)
			(end 2.2987 2.999994)
			(stroke
				(width 0.1524)
				(type default)
			)
			(layer "F.SilkS")
		)
		(fp_poly
			(pts
				(xy -2.21234 -3.631438) (xy -2.72034 -2.615438) (xy -3.22834 -3.631438)
			)
			(stroke
				(width 0)
				(type default)
			)
			(fill yes)
			(layer "F.SilkS")
		)
		(fp_line
			(start -2.500122 -2.999994)
			(end 2.500122 -2.999994)
			(stroke
				(width 0.1)
				(type default)
			)
			(layer "F.Fab")
		)
		(fp_line
			(start -2.500122 2.999994)
			(end -2.500122 -2.999994)
			(stroke
				(width 0.1)
				(type default)
			)
			(layer "F.Fab")
		)
		(fp_line
			(start 2.500122 -2.999994)
			(end 2.500122 2.999994)
			(stroke
				(width 0.1)
				(type default)
			)
			(layer "F.Fab")
		)
		(fp_line
			(start 2.500122 2.999994)
			(end -2.500122 2.999994)
			(stroke
				(width 0.1)
				(type default)
			)
			(layer "F.Fab")
		)
		(fp_poly
			(pts
				(xy -4.218432 -2.783078) (xy -4.218432 -1.767078) (xy -3.202432 -2.275078)
			)
			(stroke
				(width 0)
				(type default)
			)
			(fill yes)
			(layer "F.Fab")
		)
		(pad "1" smd rect
			(at -2.400046 -2.275078 90)
			(size 0.2286 0.6096)
			(layers "F.Cu" "F.Mask" "F.Paste")
			(net "PVCCIN_CPU0_VOS5")
		)
		(pad "2" smd rect
			(at -2.400046 -1.82499 90)
			(size 0.2286 0.6096)
			(layers "F.Cu" "F.Mask" "F.Paste")
			(net "GND")
		)
		(pad "3" smd rect
			(at -2.400046 -1.374902 90)
			(size 0.2286 0.6096)
			(layers "F.Cu" "F.Mask" "F.Paste")
			(net "PVCCIN_CPU0_VDD5")
		)
		(pad "4" smd rect
			(at -2.400046 -0.925068 90)
			(size 0.2286 0.6096)
			(layers "F.Cu" "F.Mask" "F.Paste")
			(net "PVCCIN_CPU0_PVCC")
		)
		(pad "5" smd rect
			(at -2.400046 -0.47498 90)
			(size 0.2286 0.6096)
			(layers "F.Cu" "F.Mask" "F.Paste")
			(net "GND")
		)
		(pad "6" smd rect
			(at -2.400046 -0.024892 90)
			(size 0.2286 0.6096)
			(layers "F.Cu" "F.Mask" "F.Paste")
			(net "Net_8556")
		)
		(pad "7_9-20_24" smd circle
			(at 0 1.150112 90)
			(size 0 0)
			(layers "F.Cu" "F.Mask" "F.Paste")
			(net "GND")
		)
		(pad "10_19" smd rect
			(at 0 2.899918 90)
			(size 0.6096 4.318)
			(layers "F.Cu" "F.Mask" "F.Paste")
			(net "SW_PVCCIN_CPU0_SW5")
		)
		(pad "25_29" smd rect
			(at 1.549908 -1.279906 270)
			(size 2.0574 2.3114)
			(layers "F.Cu" "F.Mask" "F.Paste")
			(net "SW_P12V_PVCCIN_CPU0_FLT")
		)
		(pad "30" smd rect
			(at 2.05994 -2.899918)
			(size 0.2286 0.6096)
			(layers "F.Cu" "F.Mask" "F.Paste")
			(net "SW_P12V_PVCCIN_CPU0_FLT")
		)
		(pad "31" smd rect
			(at 1.610106 -2.899918)
			(size 0.2286 0.6096)
			(layers "F.Cu" "F.Mask" "F.Paste")
			(net "Net_8557")
		)
		(pad "32" smd rect
			(at 1.160018 -2.899918)
			(size 0.2286 0.6096)
			(layers "F.Cu" "F.Mask" "F.Paste")
			(net "SW_PVCCIN_CPU0_BOOTR5")
		)
		(pad "33" smd rect
			(at 0.70993 -2.899918)
			(size 0.2286 0.6096)
			(layers "F.Cu" "F.Mask" "F.Paste")
			(net "SW_PVCCIN_CPU0_BOOT5")
		)
		(pad "34" smd rect
			(at 0.260096 -2.899918)
			(size 0.2286 0.6096)
			(layers "F.Cu" "F.Mask" "F.Paste")
			(net "PVCCIN_CPU0_PWM5")
		)
		(pad "35" smd rect
			(at -0.189992 -2.899918)
			(size 0.2286 0.6096)
			(layers "F.Cu" "F.Mask" "F.Paste")
			(net "PVCCIN_CPU0_VDD5")
		)
		(pad "36" smd rect
			(at -0.64008 -2.899918)
			(size 0.2286 0.6096)
			(layers "F.Cu" "F.Mask" "F.Paste")
			(net "PVCCIN_CPU0_ATSEN")
		)
		(pad "37" smd rect
			(at -1.089914 -2.899918)
			(size 0.2286 0.6096)
			(layers "F.Cu" "F.Mask" "F.Paste")
			(net "PVCCIN_CPU0_LSET5")
		)
		(pad "38" smd rect
			(at -1.540002 -2.899918)
			(size 0.2286 0.6096)
			(layers "F.Cu" "F.Mask" "F.Paste")
			(net "PVCCIN_CPU0_IMON5")
		)
		(pad "39" smd rect
			(at -1.99009 -2.899918)
			(size 0.2286 0.6096)
			(layers "F.Cu" "F.Mask" "F.Paste")
			(net "PVCCIN_CPU0_VREF")
		)
		(pad "40" smd rect
			(at -0.87503 -1.27508)
			(size 1.7526 1.9558)
			(layers "F.Cu" "F.Mask" "F.Paste")
			(net "GND")
		)
		(pad "41" smd rect
			(at -1.525016 0.249936 270)
			(size 0.3048 0.4572)
			(layers "F.Cu" "F.Mask" "F.Paste")
			(net "Net_8555")
		)
		(zone
			(layer "F.Cu")
			(hatch none 0.5)
			(connect_pads
				(clearance 0)
			)
			(min_thickness 0.25)
			(keepout
				(tracks not_allowed)
				(vias allowed)
				(pads allowed)
				(copperpour not_allowed)
				(footprints allowed)
			)
			(placement
				(enabled no)
				(sheetname "")
			)
			(fill
				(thermal_gap 0.5)
				(thermal_bridge_width 0.5)
				(island_removal_mode 0)
			)
			(polygon
				(pts
					(xy 375.079514 -334.126332) (xy 375.079514 -334.875632) (xy 380.079758 -334.875632) (xy 380.079758 -334.126332)
					(xy 379.789436 -334.126332) (xy 379.789436 -334.582008) (xy 375.369836 -334.582008) (xy 375.369836 -334.126332)
				)
			)
		)
		(zone
			(layer "F.Cu")
			(hatch none 0.5)
			(connect_pads
				(clearance 0)
			)
			(min_thickness 0.25)
			(keepout
				(tracks not_allowed)
				(vias allowed)
				(pads allowed)
				(copperpour not_allowed)
				(footprints allowed)
			)
			(placement
				(enabled no)
				(sheetname "")
			)
			(fill
				(thermal_gap 0.5)
				(thermal_bridge_width 0.5)
				(island_removal_mode 0)
			)
			(polygon
				(pts
					(xy 375.53519 -337.429348) (xy 375.777506 -337.429348) (xy 375.777506 -337.372706) (xy 376.46356 -337.372706)
					(xy 376.46356 -337.058508) (xy 376.628914 -337.058508) (xy 376.628914 -336.377026) (xy 375.079514 -336.377026)
					(xy 375.079514 -336.833718) (xy 375.77522 -336.833718) (xy 375.77522 -336.67319) (xy 376.33402 -336.67319)
					(xy 376.33402 -337.07959) (xy 375.77522 -337.07959) (xy 375.77522 -336.859118) (xy 375.079514 -336.859118)
					(xy 375.079514 -336.986118) (xy 375.53519 -336.986118)
				)
			)
		)
	)
	(footprint ""
		(layer "F.Cu")
		(at 106.70921 -412.671768 180)
		(property "Reference" "R3355"
			(at 0 0 180)
			(layer "F.SilkS")
			(hide yes)
			(effects
				(font
					(size 1.27 1.27)
				)
			)
		)
		(property "Value" ""
			(at 0 0 180)
			(layer "F.Fab")
			(effects
				(font
					(size 1.27 1.27)
				)
			)
		)
		(duplicate_pad_numbers_are_jumpers no)
		(fp_line
			(start 0.7874 -0.4064)
			(end 0.7874 -0.00762)
			(stroke
				(width 0.1524)
				(type default)
			)
			(layer "F.SilkS")
		)
		(fp_line
			(start 0.43307 0.4064)
			(end -0.49149 0.4064)
			(stroke
				(width 0.1524)
				(type default)
			)
			(layer "F.SilkS")
		)
		(fp_line
			(start -0.7874 0.05842)
			(end -0.7874 -0.4064)
			(stroke
				(width 0.1524)
				(type default)
			)
			(layer "F.SilkS")
		)
		(fp_line
			(start -0.7874 -0.4064)
			(end 0.7874 -0.4064)
			(stroke
				(width 0.1524)
				(type default)
			)
			(layer "F.SilkS")
		)
		(fp_line
			(start 0.67945 0.3048)
			(end 0.120396 0.3048)
			(stroke
				(width 0.1)
				(type default)
			)
			(layer "F.Fab")
		)
		(fp_line
			(start 0.67945 -0.3048)
			(end 0.67945 0.3048)
			(stroke
				(width 0.1)
				(type default)
			)
			(layer "F.Fab")
		)
		(fp_line
			(start 0.12065 -0.2794)
			(end 0.12065 -0.3048)
			(stroke
				(width 0.1)
				(type default)
			)
			(layer "F.Fab")
		)
		(fp_line
			(start 0.12065 -0.3048)
			(end 0.67945 -0.3048)
			(stroke
				(width 0.1)
				(type default)
			)
			(layer "F.Fab")
		)
		(fp_line
			(start 0.120396 0.3048)
			(end 0.120396 0.2794)
			(stroke
				(width 0.1)
				(type default)
			)
			(layer "F.Fab")
		)
		(fp_line
			(start 0.120396 0.2794)
			(end -0.12065 0.2794)
			(stroke
				(width 0.1)
				(type default)
			)
			(layer "F.Fab")
		)
		(fp_line
			(start -0.12065 0.3048)
			(end -0.67945 0.3048)
			(stroke
				(width 0.1)
				(type default)
			)
			(layer "F.Fab")
		)
		(fp_line
			(start -0.12065 0.2794)
			(end -0.12065 0.3048)
			(stroke
				(width 0.1)
				(type default)
			)
			(layer "F.Fab")
		)
		(fp_line
			(start -0.12065 -0.2794)
			(end 0.12065 -0.2794)
			(stroke
				(width 0.1)
				(type default)
			)
			(layer "F.Fab")
		)
		(fp_line
			(start -0.12065 -0.305054)
			(end -0.12065 -0.2794)
			(stroke
				(width 0.1)
				(type default)
			)
			(layer "F.Fab")
		)
		(fp_line
			(start -0.67945 0.3048)
			(end -0.67945 -0.305054)
			(stroke
				(width 0.1)
				(type default)
			)
			(layer "F.Fab")
		)
		(fp_line
			(start -0.67945 -0.305054)
			(end -0.12065 -0.305054)
			(stroke
				(width 0.1)
				(type default)
			)
			(layer "F.Fab")
		)
		(pad "1" smd circle
			(at -0.40005 0 180)
			(size 0 0)
			(layers "F.Cu" "F.Mask" "F.Paste")
			(net "CLK_100M_GPU_2_R_DN")
		)
		(pad "2" smd circle
			(at 0.40005 0 180)
			(size 0 0)
			(layers "F.Cu" "F.Mask" "F.Paste")
			(net "CLK_100M_GPU_2_DN")
		)
	)
	(footprint ""
		(layer "F.Cu")
		(at 176.080928 -418.806122)
		(property "Reference" "R3433"
			(at 0 0 0)
			(layer "F.SilkS")
			(hide yes)
			(effects
				(font
					(size 1.27 1.27)
				)
			)
		)
		(property "Value" ""
			(at 0 0 0)
			(layer "F.Fab")
			(effects
				(font
					(size 1.27 1.27)
				)
			)
		)
		(duplicate_pad_numbers_are_jumpers no)
		(fp_line
			(start -0.7874 -0.4064)
			(end 0.7874 -0.4064)
			(stroke
				(width 0.1524)
				(type default)
			)
			(layer "F.SilkS")
		)
		(fp_line
			(start -0.7874 0.4064)
			(end -0.7874 -0.4064)
			(stroke
				(width 0.1524)
				(type default)
			)
			(layer "F.SilkS")
		)
		(fp_line
			(start 0.7874 -0.4064)
			(end 0.7874 0.4064)
			(stroke
				(width 0.1524)
				(type default)
			)
			(layer "F.SilkS")
		)
		(fp_line
			(start 0.7874 0.4064)
			(end -0.7874 0.4064)
			(stroke
				(width 0.1524)
				(type default)
			)
			(layer "F.SilkS")
		)
		(fp_line
			(start -0.67945 -0.305054)
			(end -0.12065 -0.305054)
			(stroke
				(width 0.1)
				(type default)
			)
			(layer "F.Fab")
		)
		(fp_line
			(start -0.67945 0.3048)
			(end -0.67945 -0.305054)
			(stroke
				(width 0.1)
				(type default)
			)
			(layer "F.Fab")
		)
		(fp_line
			(start -0.12065 -0.305054)
			(end -0.12065 -0.2794)
			(stroke
				(width 0.1)
				(type default)
			)
			(layer "F.Fab")
		)
		(fp_line
			(start -0.12065 -0.2794)
			(end 0.12065 -0.2794)
			(stroke
				(width 0.1)
				(type default)
			)
			(layer "F.Fab")
		)
		(fp_line
			(start -0.12065 0.2794)
			(end -0.12065 0.3048)
			(stroke
				(width 0.1)
				(type default)
			)
			(layer "F.Fab")
		)
		(fp_line
			(start -0.12065 0.3048)
			(end -0.67945 0.3048)
			(stroke
				(width 0.1)
				(type default)
			)
			(layer "F.Fab")
		)
		(fp_line
			(start 0.120396 0.2794)
			(end -0.12065 0.2794)
			(stroke
				(width 0.1)
				(type default)
			)
			(layer "F.Fab")
		)
		(fp_line
			(start 0.120396 0.3048)
			(end 0.120396 0.2794)
			(stroke
				(width 0.1)
				(type default)
			)
			(layer "F.Fab")
		)
		(fp_line
			(start 0.12065 -0.3048)
			(end 0.67945 -0.3048)
			(stroke
				(width 0.1)
				(type default)
			)
			(layer "F.Fab")
		)
		(fp_line
			(start 0.12065 -0.2794)
			(end 0.12065 -0.3048)
			(stroke
				(width 0.1)
				(type default)
			)
			(layer "F.Fab")
		)
		(fp_line
			(start 0.67945 -0.3048)
			(end 0.67945 0.3048)
			(stroke
				(width 0.1)
				(type default)
			)
			(layer "F.Fab")
		)
		(fp_line
			(start 0.67945 0.3048)
			(end 0.120396 0.3048)
			(stroke
				(width 0.1)
				(type default)
			)
			(layer "F.Fab")
		)
		(pad "1" smd circle
			(at -0.40005 0)
			(size 0 0)
			(layers "F.Cu" "F.Mask" "F.Paste")
			(net "P3V3_AUX")
		)
		(pad "2" smd circle
			(at 0.40005 0)
			(size 0 0)
			(layers "F.Cu" "F.Mask" "F.Paste")
			(net "GPU_BASE_HMC_READY_N")
		)
	)
	(footprint ""
		(layer "F.Cu")
		(at 80.925162 -25.358598 180)
		(property "Reference" "PR4522"
			(at 0 0 180)
			(layer "F.SilkS")
			(hide yes)
			(effects
				(font
					(size 1.27 1.27)
				)
			)
		)
		(property "Value" ""
			(at 0 0 180)
			(layer "F.Fab")
			(effects
				(font
					(size 1.27 1.27)
				)
			)
		)
		(duplicate_pad_numbers_are_jumpers no)
		(fp_line
			(start 0.7874 0.4064)
			(end -0.7874 0.4064)
			(stroke
				(width 0.1524)
				(type default)
			)
			(layer "F.SilkS")
		)
		(fp_line
			(start 0.7874 -0.4064)
			(end 0.7874 0.4064)
			(stroke
				(width 0.1524)
				(type default)
			)
			(layer "F.SilkS")
		)
		(fp_line
			(start -0.7874 0.4064)
			(end -0.7874 -0.4064)
			(stroke
				(width 0.1524)
				(type default)
			)
			(layer "F.SilkS")
		)
		(fp_line
			(start -0.7874 -0.4064)
			(end 0.7874 -0.4064)
			(stroke
				(width 0.1524)
				(type default)
			)
			(layer "F.SilkS")
		)
		(fp_line
			(start 0.67945 0.3048)
			(end 0.120396 0.3048)
			(stroke
				(width 0.1)
				(type default)
			)
			(layer "F.Fab")
		)
		(fp_line
			(start 0.67945 -0.3048)
			(end 0.67945 0.3048)
			(stroke
				(width 0.1)
				(type default)
			)
			(layer "F.Fab")
		)
		(fp_line
			(start 0.12065 -0.2794)
			(end 0.12065 -0.3048)
			(stroke
				(width 0.1)
				(type default)
			)
			(layer "F.Fab")
		)
		(fp_line
			(start 0.12065 -0.3048)
			(end 0.67945 -0.3048)
			(stroke
				(width 0.1)
				(type default)
			)
			(layer "F.Fab")
		)
		(fp_line
			(start 0.120396 0.3048)
			(end 0.120396 0.2794)
			(stroke
				(width 0.1)
				(type default)
			)
			(layer "F.Fab")
		)
		(fp_line
			(start 0.120396 0.2794)
			(end -0.12065 0.2794)
			(stroke
				(width 0.1)
				(type default)
			)
			(layer "F.Fab")
		)
		(fp_line
			(start -0.12065 0.3048)
			(end -0.67945 0.3048)
			(stroke
				(width 0.1)
				(type default)
			)
			(layer "F.Fab")
		)
		(fp_line
			(start -0.12065 0.2794)
			(end -0.12065 0.3048)
			(stroke
				(width 0.1)
				(type default)
			)
			(layer "F.Fab")
		)
		(fp_line
			(start -0.12065 -0.2794)
			(end 0.12065 -0.2794)
			(stroke
				(width 0.1)
				(type default)
			)
			(layer "F.Fab")
		)
		(fp_line
			(start -0.12065 -0.305054)
			(end -0.12065 -0.2794)
			(stroke
				(width 0.1)
				(type default)
			)
			(layer "F.Fab")
		)
		(fp_line
			(start -0.67945 0.3048)
			(end -0.67945 -0.305054)
			(stroke
				(width 0.1)
				(type default)
			)
			(layer "F.Fab")
		)
		(fp_line
			(start -0.67945 -0.305054)
			(end -0.12065 -0.305054)
			(stroke
				(width 0.1)
				(type default)
			)
			(layer "F.Fab")
		)
		(pad "1" smd circle
			(at -0.40005 0 180)
			(size 0 0)
			(layers "F.Cu" "F.Mask" "F.Paste")
			(net "P12V_OCP_V3_2")
		)
		(pad "2" smd circle
			(at 0.40005 0 180)
			(size 0 0)
			(layers "F.Cu" "F.Mask" "F.Paste")
			(net "P12V_OCP_GATE_2")
		)
	)
	(footprint ""
		(layer "F.Cu")
		(at 124.538994 -408.517344 -90)
		(property "Reference" "C1518"
			(at 0 0 270)
			(layer "F.SilkS")
			(hide yes)
			(effects
				(font
					(size 1.27 1.27)
				)
			)
		)
		(property "Value" ""
			(at 0 0 270)
			(layer "F.Fab")
			(effects
				(font
					(size 1.27 1.27)
				)
			)
		)
		(duplicate_pad_numbers_are_jumpers no)
		(fp_line
			(start -0.299974 0.150114)
			(end -0.299974 -0.150114)
			(stroke
				(width 0.1)
				(type default)
			)
			(layer "F.Fab")
		)
		(fp_line
			(start 0.299974 0.150114)
			(end -0.299974 0.150114)
			(stroke
				(width 0.1)
				(type default)
			)
			(layer "F.Fab")
		)
		(fp_line
			(start -0.299974 -0.150114)
			(end 0.299974 -0.150114)
			(stroke
				(width 0.1)
				(type default)
			)
			(layer "F.Fab")
		)
		(fp_line
			(start 0.299974 -0.150114)
			(end 0.299974 0.150114)
			(stroke
				(width 0.1)
				(type default)
			)
			(layer "F.Fab")
		)
		(pad "1" smd rect
			(at -0.2667 0 270)
			(size 0.3048 0.381)
			(layers "F.Cu" "F.Mask" "F.Paste")
			(net "P5E_CPU1_PE3_TX_C_DN<14>")
		)
		(pad "2" smd rect
			(at 0.2667 0 270)
			(size 0.3048 0.381)
			(layers "F.Cu" "F.Mask" "F.Paste")
			(net "P5E_CPU1_PE3_TX_DN<14>")
		)
	)
)
